# T6G (Grand Teton) — schematic netlist excerpt (pin names and nets, part order shuffled) for the footprints in the layout excerpt that follows; sources: Cadence DE-HDL packaged netlist, KiCad conversion of 04192023_DAF0TMB3IC0_F0TG_MB_C_brd_V02_OCP.brd

J15  SCONN288_DDR506112002KQ  IO  pkg DDR288S_1-1VXC  page 87
  VIN_BULK0  = P12V_MEM_CPU0
  RFU0  = NC
  VIN_MGMT  = P3V3_AUX
  HSCL  = I3C_SPD_DDRB_CPU0_SCL
  HSDA  = I3C_SPD_DDRB_CPU0_SDA
  VSS0  = GND
  DQ0_A  = M_B_CPU0_SA_DQ<0>
  VSS1  = GND
  DQ1_A  = M_B_CPU0_SA_DQ<1>
  VSS2  = GND
  DQS0_A_T  = M_B_CPU0_SA_DQS_DP<0>
  DQS0_A_C  = M_B_CPU0_SA_DQS_DN<0>
  VSS3  = GND
  DQ4_A  = M_B_CPU0_SA_DQ<4>
  VSS4  = GND
  DQ5_A  = M_B_CPU0_SA_DQ<5>
  VSS5  = GND
  DQ8_A  = M_B_CPU0_SA_DQ<8>
  VSS6  = GND
  DQ9_A  = M_B_CPU0_SA_DQ<9>
  VSS7  = GND
  DQS1_A_T  = M_B_CPU0_SA_DQS_DP<1>
  DQS1_A_C  = M_B_CPU0_SA_DQS_DN<1>
  VSS8  = GND
  DQ12_A  = M_B_CPU0_SA_DQ<12>
  VSS9  = GND
  DQ13_A  = M_B_CPU0_SA_DQ<13>
  VSS10  = GND
  DQ16_A  = M_B_CPU0_SA_DQ<16>
  VSS11  = GND
  DQ17_A  = M_B_CPU0_SA_DQ<17>
  VSS12  = GND
  DQS2_A_T  = M_B_CPU0_SA_DQS_DP<2>
  DQS2_A_C  = M_B_CPU0_SA_DQS_DN<2>
  VSS13  = GND
  DQ20_A  = M_B_CPU0_SA_DQ<20>
  VSS14  = GND
  DQ21_A  = M_B_CPU0_SA_DQ<21>
  VSS15  = GND
  DQ24_A  = M_B_CPU0_SA_DQ<24>
  VSS16  = GND
  DQ25_A  = M_B_CPU0_SA_DQ<25>
  VSS17  = GND
  DQS3_A_T  = M_B_CPU0_SA_DQS_DP<3>
  DQS3_A_C  = M_B_CPU0_SA_DQS_DN<3>
  VSS18  = GND
  DQ28_A  = M_B_CPU0_SA_DQ<28>
  VSS19  = GND
  DQ29_A  = M_B_CPU0_SA_DQ<29>
  VSS20  = GND
  CB0_A  = M_B_CPU0_SA_CB<0>
  VSS21  = GND
  CB1_A  = M_B_CPU0_SA_CB<1>
  VSS22  = GND
  DQS4_A_T  = M_B_CPU0_SA_DQS_DP<4>
  DQS4_A_C  = M_B_CPU0_SA_DQS_DN<4>
  VSS23  = GND
  CB4_A  = M_B_CPU0_SA_CB<4>
  VSS24  = GND
  CB5_A  = M_B_CPU0_SA_CB<5>
  VSS25  = GND
  ALERT_N  = M_B_CPU0_ALERT_N
  VSS26  = GND
  CS0_A_N  = M_B_CPU0_SA_CS_N<0>
  VSS27  = GND
  CA0_A  = M_B_CPU0_SA_CA<0>
  VSS28  = GND
  CA2_A  = M_B_CPU0_SA_CA<2>
  VSS29  = GND
  CA4_A  = M_B_CPU0_SA_CA<4>
  VSS30  = GND
  CA6_A  = M_B_CPU0_SA_CA<6>
  VSS31  = GND
  PAR_A  = M_B_CPU0_SA_PAR
  VSS32  = GND
  CA0_B  = M_B_CPU0_SB_CA<0>
  VSS33  = GND
  CA2_B  = M_B_CPU0_SB_CA<2>
  VSS34  = GND
  CA4_B  = M_B_CPU0_SB_CA<4>
  VSS35  = GND
  CA6_B  = M_B_CPU0_SB_CA<6>
  VSS36  = GND
  CS0_B_N  = M_B_CPU0_SB_CS_N<0>
  VSS37  = GND
  \lbd||rsp_a_n\  = M_B_CPU0_SA_RSP<0>
  \lbs||rsp_b_n\  = M_B_CPU0_SB_RSP<0>
  VSS38  = GND
  CB4_B  = M_B_CPU0_SB_CB<4>
  VSS39  = GND
  CB5_B  = M_B_CPU0_SB_CB<5>
  VSS40  = GND
  \dqs9_b_t||tdqs9_b_t||dbi4_b_n\  = M_B_CPU0_SB_DQS_DP<9>
  \dqs9_b_c||tdqs9_b_c\  = M_B_CPU0_SB_DQS_DN<9>
  VSS41  = GND
  CB0_B  = M_B_CPU0_SB_CB<0>
  VSS42  = GND
  CB1_B  = M_B_CPU0_SB_CB<1>
  VSS43  = GND
  DQ0_B  = M_B_CPU0_SB_DQ<0>
  VSS44  = GND
  DQ1_B  = M_B_CPU0_SB_DQ<1>
  VSS45  = GND
  DQS0_B_T  = M_B_CPU0_SB_DQS_DP<0>
  DQS0_B_C  = M_B_CPU0_SB_DQS_DN<0>
  VSS46  = GND
  DQ4_B  = M_B_CPU0_SB_DQ<4>
  VSS47  = GND
  DQ5_B  = M_B_CPU0_SB_DQ<5>
  VSS48  = GND
  DQ8_B  = M_B_CPU0_SB_DQ<8>
  VSS49  = GND
  DQ9_B  = M_B_CPU0_SB_DQ<9>
  VSS50  = GND
  DQS1_B_T  = M_B_CPU0_SB_DQS_DP<1>
  DQS1_B_C  = M_B_CPU0_SB_DQS_DN<1>
  VSS51  = GND
  DQ12_B  = M_B_CPU0_SB_DQ<12>
  VSS52  = GND
  DQ13_B  = M_B_CPU0_SB_DQ<13>
  VSS53  = GND
  DQ16_B  = M_B_CPU0_SB_DQ<16>
  VSS54  = GND
  DQ17_B  = M_B_CPU0_SB_DQ<17>
  VSS55  = GND
  DQS2_B_T  = M_B_CPU0_SB_DQS_DP<2>
  DQS2_B_C  = M_B_CPU0_SB_DQS_DN<2>
  VSS56  = GND
  DQ20_B  = M_B_CPU0_SB_DQ<20>
  VSS57  = GND
  DQ21_B  = M_B_CPU0_SB_DQ<21>
  VSS58  = GND
  DQ24_B  = M_B_CPU0_SB_DQ<24>
  VSS59  = GND
  DQ25_B  = M_B_CPU0_SB_DQ<25>
  VSS60  = GND
  DQS3_B_T  = M_B_CPU0_SB_DQS_DP<3>
  DQS3_B_C  = M_B_CPU0_SB_DQS_DN<3>
  VSS61  = GND
  DQ28_B  = M_B_CPU0_SB_DQ<28>
  VSS62  = GND
  DQ29_B  = M_B_CPU0_SB_DQ<29>
  VSS63  = GND
  RFU1  = NC
  VIN_BULK1  = P12V_MEM_CPU0
  VIN_BULK2  = P12V_MEM_CPU0
  \pwr_good||fail_n\  = PWRGD_CHB_CPU0_DIMM
  HAS  = PD_CHB_CPU0_DIMM_SAA
  RFU2  = NC
  RFU3  = NC
  VSS64  = GND
  DQ2_A  = M_B_CPU0_SA_DQ<2>
  VSS65  = GND
  DQ3_A  = M_B_CPU0_SA_DQ<3>
  VSS66  = GND
  \dqs5_a_c||tdqs5_a_c||dqs5_a_t||tdqs5_a_t\  = M_B_CPU0_SA_DQS_DN<5>
  \dqs5_a_t||tdqs5_a_t\  = M_B_CPU0_SA_DQS_DP<5>
  VSS67  = GND
  DQ6_A  = M_B_CPU0_SA_DQ<6>
  VSS68  = GND
  DQ7_A  = M_B_CPU0_SA_DQ<7>
  VSS69  = GND
  DQ10_A  = M_B_CPU0_SA_DQ<10>
  VSS70  = GND
  DQ11_A  = M_B_CPU0_SA_DQ<11>
  VSS71  = GND
  \dqs6_a_c||tdqs6_a_c||dqs6_a_t||tdqs6_a_t\  = M_B_CPU0_SA_DQS_DN<6>
  \dqs6_a_t||tdqs6_a_t\  = M_B_CPU0_SA_DQS_DP<6>
  VSS72  = GND
  DQ14_A  = M_B_CPU0_SA_DQ<14>
  VSS73  = GND
  DQ15_A  = M_B_CPU0_SA_DQ<15>
  VSS74  = GND
  DQ18_A  = M_B_CPU0_SA_DQ<18>
  VSS75  = GND
  DQ19_A  = M_B_CPU0_SA_DQ<19>
  VSS76  = GND
  \dqs7_a_c||tdqs7_a_c\  = M_B_CPU0_SA_DQS_DN<7>
  \dqs7_a_t||tdqs7_a_t\  = M_B_CPU0_SA_DQS_DP<7>
  VSS77  = GND
  DQ22_A  = M_B_CPU0_SA_DQ<22>
  VSS78  = GND
  DQ23_A  = M_B_CPU0_SA_DQ<23>
  VSS79  = GND
  DQ26_A  = M_B_CPU0_SA_DQ<26>
  VSS80  = GND
  DQ27_A  = M_B_CPU0_SA_DQ<27>
  VSS81  = GND
  \dqs8_a_c||tdqs8_a_c\  = M_B_CPU0_SA_DQS_DN<8>
  \dqs8_a_t||tdqs8_a_t\  = M_B_CPU0_SA_DQS_DP<8>
  VSS82  = GND
  DQ30_A  = M_B_CPU0_SA_DQ<30>
  VSS83  = GND
  DQ31_A  = M_B_CPU0_SA_DQ<31>
  VSS84  = GND
  CB2_A  = M_B_CPU0_SA_CB<2>
  VSS85  = GND
  CB3_A  = M_B_CPU0_SA_CB<3>
  VSS86  = GND
  \dqs9_a_c||tdqs9_a_c\  = M_B_CPU0_SA_DQS_DN<9>
  \dqs9_a_t||tdqs9_a_t\  = M_B_CPU0_SA_DQS_DP<9>
  VSS87  = GND
  CB6_A  = M_B_CPU0_SA_CB<6>
  VSS88  = GND
  CB7_A  = M_B_CPU0_SA_CB<7>
  VSS89  = GND
  RESET_N  = M_B_CPU0_RESET_N
  VSS90  = GND
  CS1_A_N  = M_B_CPU0_SA_CS_N<1>
  VSS91  = GND
  CA1_A  = M_B_CPU0_SA_CA<1>
  VSS92  = GND
  CA3_A  = M_B_CPU0_SA_CA<3>
  VSS93  = GND
  CA5_A  = M_B_CPU0_SA_CA<5>
  VSS94  = GND
  CK_T  = M_B_CPU0_CLK_DP<0>
  CK_C  = M_B_CPU0_CLK_DN<0>
  VSS95  = GND
  RFU4  = NC
  CA1_B  = M_B_CPU0_SB_CA<1>
  VSS96  = GND
  CA3_B  = M_B_CPU0_SB_CA<3>
  VSS97  = GND
  CA5_B  = M_B_CPU0_SB_CA<5>
  VSS98  = GND
  PAR_B  = M_B_CPU0_SB_PAR
  VSS99  = GND
  CS1_B_N  = M_B_CPU0_SB_CS_N<1>
  VSS100  = GND
  RFU5  = NC
  RFU6  = NC
  VSS101  = GND
  CB6_B  = M_B_CPU0_SB_CB<6>
  VSS102  = GND
  CB7_B  = M_B_CPU0_SB_CB<7>
  VSS103  = GND
  DQS4_B_C  = M_B_CPU0_SB_DQS_DN<4>
  DQS4_B_T  = M_B_CPU0_SB_DQS_DP<4>
  VSS104  = GND
  CB2_B  = M_B_CPU0_SB_CB<2>
  VSS105  = GND
  CB3_B  = M_B_CPU0_SB_CB<3>
  VSS106  = GND
  DQ2_B  = M_B_CPU0_SB_DQ<2>
  VSS107  = GND
  DQ3_B  = M_B_CPU0_SB_DQ<3>
  VSS108  = GND
  \dqs5_b_c||tdqs5_b_c\  = M_B_CPU0_SB_DQS_DN<5>
  \dqs5_b_t||tdqs5_b_t\  = M_B_CPU0_SB_DQS_DP<5>
  VSS109  = GND
  DQ6_B  = M_B_CPU0_SB_DQ<6>
  VSS110  = GND
  DQ7_B  = M_B_CPU0_SB_DQ<7>
  VSS111  = GND
  DQ10_B  = M_B_CPU0_SB_DQ<10>
  VSS112  = GND
  DQ11_B  = M_B_CPU0_SB_DQ<11>
  VSS113  = GND
  \dqs6_b_c||tdqs6_b_c\  = M_B_CPU0_SB_DQS_DN<6>
  \dqs6_b_t||tdqs6_b_t\  = M_B_CPU0_SB_DQS_DP<6>
  VSS114  = GND
  DQ14_B  = M_B_CPU0_SB_DQ<14>
  VSS115  = GND
  DQ15_B  = M_B_CPU0_SB_DQ<15>
  VSS116  = GND
  DQ18_B  = M_B_CPU0_SB_DQ<18>
  VSS117  = GND
  DQ19_B  = M_B_CPU0_SB_DQ<19>
  VSS118  = GND
  \dqs7_b_c||tdqs7_b_c\  = M_B_CPU0_SB_DQS_DN<7>
  \dqs7_b_t||tdqs7_b_t\  = M_B_CPU0_SB_DQS_DP<7>
  VSS119  = GND
  DQ22_B  = M_B_CPU0_SB_DQ<22>
  VSS120  = GND
  DQ23_B  = M_B_CPU0_SB_DQ<23>
  VSS121  = GND
  DQ26_B  = M_B_CPU0_SB_DQ<26>
  VSS122  = GND
  DQ27_B  = M_B_CPU0_SB_DQ<27>
  VSS123  = GND
  \dqs8_b_c||tdqs8_b_c\  = M_B_CPU0_SB_DQS_DN<8>
  \dqs8_b_t||tdqs8_b_t\  = M_B_CPU0_SB_DQS_DP<8>
  VSS124  = GND
  DQ30_B  = M_B_CPU0_SB_DQ<30>
  VSS125  = GND
  DQ31_B  = M_B_CPU0_SB_DQ<31>
  VSS126  = GND
  G1  = GND
  G2  = GND
  G3  = GND

(kicad_pcb
	(version 20260206)
	(generator "pcbnew")
	(generator_version "10.0")
	(general
		(thickness 1.6)
		(legacy_teardrops no)
	)
	(paper "A4")
	(title_block
		(title "04192023_DAF0TMB3IC0_F0TG_MB_C_brd_V02_OCP.brd")
		(comment 1 "Grand Teton / footprint 1120 of 8354 (J15), pads 93-138 of 291")
	)
	(layers
		(0 "F.Cu" signal "TOP")
		(4 "In1.Cu" signal "GND")
		(6 "In2.Cu" signal "IN1")
		(8 "In3.Cu" signal "GND1")
		(10 "In4.Cu" signal "IN2")
		(12 "In5.Cu" signal "GND2")
		(14 "In6.Cu" signal "IN3")
		(16 "In7.Cu" signal "GND3")
		(18 "In8.Cu" signal "VCC")
		(20 "In9.Cu" signal "VCC1")
		(22 "In10.Cu" signal "GND4")
		(24 "In11.Cu" signal "IN4")
		(26 "In12.Cu" signal "GND5")
		(28 "In13.Cu" signal "IN5")
		(30 "In14.Cu" signal "GND6")
		(32 "In15.Cu" signal "IN6")
		(34 "In16.Cu" signal "GND7")
		(2 "B.Cu" signal "BOTTOM")
		(9 "F.Adhes" user "F.Adhesive")
		(11 "B.Adhes" user "B.Adhesive")
		(13 "F.Paste" user "Package Geometry/Pastemask Top")
		(15 "B.Paste" user "Package Geometry/Pastemask Bottom")
		(5 "F.SilkS" user "Ref Des/Silkscreen Top")
		(7 "B.SilkS" user "Ref Des/Silkscreen Bottom")
		(1 "F.Mask" user "Board Geometry/Soldermask Top")
		(3 "B.Mask" user "Board Geometry/Soldermask Bottom")
		(17 "Dwgs.User" user "User.Drawings")
		(19 "Cmts.User" user "User.Comments")
		(21 "Eco1.User" user "User.Eco1")
		(23 "Eco2.User" user "User.Eco2")
		(25 "Edge.Cuts" user "Board Geometry/Outline")
		(27 "Margin" user)
		(31 "F.CrtYd" user "Package Geometry/Place Bound Top")
		(29 "B.CrtYd" user "Package Geometry/Place Bound Bottom")
		(35 "F.Fab" user "Ref Des/Assembly Top")
		(33 "B.Fab" user "Ref Des/Assembly Bottom")
	)
	(footprint ""
		(layer "F.Cu")
		(at 297.774106 -255.560068 180)
		(property "Reference" "J15"
			(at -2.2098 -81.984088 0)
			(unlocked yes)
			(layer "F.SilkS")
			(effects
				(font
					(size 0.7874 0.5842)
					(thickness 0.1524)
				)
			)
		)
		(property "Value" ""
			(at 0 0 180)
			(layer "F.Fab")
			(effects
				(font
					(size 1.27 1.27)
				)
			)
		)
		(duplicate_pad_numbers_are_jumpers no)
		(pad "93" smd rect
			(at -2.050034 19.975068 90)
			(size 0.519938 1.4986)
			(layers "F.Cu" "F.Mask" "F.Paste")
			(net "M_B_CPU0_SB_DQS_DP<9>")
		)
		(pad "94" smd rect
			(at -2.050034 20.824952 90)
			(size 0.519938 1.4986)
			(layers "F.Cu" "F.Mask" "F.Paste")
			(net "M_B_CPU0_SB_DQS_DN<9>")
		)
		(pad "95" smd rect
			(at -2.050034 21.67509 90)
			(size 0.519938 1.4986)
			(layers "F.Cu" "F.Mask" "F.Paste")
			(net "GND")
		)
		(pad "96" smd rect
			(at -2.050034 22.524974 90)
			(size 0.519938 1.4986)
			(layers "F.Cu" "F.Mask" "F.Paste")
			(net "M_B_CPU0_SB_CB<0>")
		)
		(pad "97" smd rect
			(at -2.050034 23.375112 90)
			(size 0.519938 1.4986)
			(layers "F.Cu" "F.Mask" "F.Paste")
			(net "GND")
		)
		(pad "98" smd rect
			(at -2.050034 24.224996 90)
			(size 0.519938 1.4986)
			(layers "F.Cu" "F.Mask" "F.Paste")
			(net "M_B_CPU0_SB_CB<1>")
		)
		(pad "99" smd rect
			(at -2.050034 25.07488 90)
			(size 0.519938 1.4986)
			(layers "F.Cu" "F.Mask" "F.Paste")
			(net "GND")
		)
		(pad "100" smd rect
			(at -2.050034 25.925018 90)
			(size 0.519938 1.4986)
			(layers "F.Cu" "F.Mask" "F.Paste")
			(net "M_B_CPU0_SB_DQ<0>")
		)
		(pad "101" smd rect
			(at -2.050034 26.774902 90)
			(size 0.519938 1.4986)
			(layers "F.Cu" "F.Mask" "F.Paste")
			(net "GND")
		)
		(pad "102" smd rect
			(at -2.050034 27.62504 90)
			(size 0.519938 1.4986)
			(layers "F.Cu" "F.Mask" "F.Paste")
			(net "M_B_CPU0_SB_DQ<1>")
		)
		(pad "103" smd rect
			(at -2.050034 28.474924 90)
			(size 0.519938 1.4986)
			(layers "F.Cu" "F.Mask" "F.Paste")
			(net "GND")
		)
		(pad "104" smd rect
			(at -2.050034 29.325062 90)
			(size 0.519938 1.4986)
			(layers "F.Cu" "F.Mask" "F.Paste")
			(net "M_B_CPU0_SB_DQS_DP<0>")
		)
		(pad "105" smd rect
			(at -2.050034 30.174946 90)
			(size 0.519938 1.4986)
			(layers "F.Cu" "F.Mask" "F.Paste")
			(net "M_B_CPU0_SB_DQS_DN<0>")
		)
		(pad "106" smd rect
			(at -2.050034 31.025084 90)
			(size 0.519938 1.4986)
			(layers "F.Cu" "F.Mask" "F.Paste")
			(net "GND")
		)
		(pad "107" smd rect
			(at -2.050034 31.874968 90)
			(size 0.519938 1.4986)
			(layers "F.Cu" "F.Mask" "F.Paste")
			(net "M_B_CPU0_SB_DQ<4>")
		)
		(pad "108" smd rect
			(at -2.050034 32.725106 90)
			(size 0.519938 1.4986)
			(layers "F.Cu" "F.Mask" "F.Paste")
			(net "GND")
		)
		(pad "109" smd rect
			(at -2.050034 33.57499 90)
			(size 0.519938 1.4986)
			(layers "F.Cu" "F.Mask" "F.Paste")
			(net "M_B_CPU0_SB_DQ<5>")
		)
		(pad "110" smd rect
			(at -2.050034 34.425128 90)
			(size 0.519938 1.4986)
			(layers "F.Cu" "F.Mask" "F.Paste")
			(net "GND")
		)
		(pad "111" smd rect
			(at -2.050034 35.275012 90)
			(size 0.519938 1.4986)
			(layers "F.Cu" "F.Mask" "F.Paste")
			(net "M_B_CPU0_SB_DQ<8>")
		)
		(pad "112" smd rect
			(at -2.050034 36.124896 90)
			(size 0.519938 1.4986)
			(layers "F.Cu" "F.Mask" "F.Paste")
			(net "GND")
		)
		(pad "113" smd rect
			(at -2.050034 36.975034 90)
			(size 0.519938 1.4986)
			(layers "F.Cu" "F.Mask" "F.Paste")
			(net "M_B_CPU0_SB_DQ<9>")
		)
		(pad "114" smd rect
			(at -2.050034 37.824918 90)
			(size 0.519938 1.4986)
			(layers "F.Cu" "F.Mask" "F.Paste")
			(net "GND")
		)
		(pad "115" smd rect
			(at -2.050034 38.675056 90)
			(size 0.519938 1.4986)
			(layers "F.Cu" "F.Mask" "F.Paste")
			(net "M_B_CPU0_SB_DQS_DP<1>")
		)
		(pad "116" smd rect
			(at -2.050034 39.52494 90)
			(size 0.519938 1.4986)
			(layers "F.Cu" "F.Mask" "F.Paste")
			(net "M_B_CPU0_SB_DQS_DN<1>")
		)
		(pad "117" smd rect
			(at -2.050034 40.375078 90)
			(size 0.519938 1.4986)
			(layers "F.Cu" "F.Mask" "F.Paste")
			(net "GND")
		)
		(pad "118" smd rect
			(at -2.050034 41.224962 90)
			(size 0.519938 1.4986)
			(layers "F.Cu" "F.Mask" "F.Paste")
			(net "M_B_CPU0_SB_DQ<12>")
		)
		(pad "119" smd rect
			(at -2.050034 42.0751 90)
			(size 0.519938 1.4986)
			(layers "F.Cu" "F.Mask" "F.Paste")
			(net "GND")
		)
		(pad "120" smd rect
			(at -2.050034 42.924984 90)
			(size 0.519938 1.4986)
			(layers "F.Cu" "F.Mask" "F.Paste")
			(net "M_B_CPU0_SB_DQ<13>")
		)
		(pad "121" smd rect
			(at -2.050034 43.775122 90)
			(size 0.519938 1.4986)
			(layers "F.Cu" "F.Mask" "F.Paste")
			(net "GND")
		)
		(pad "122" smd rect
			(at -2.050034 44.625006 90)
			(size 0.519938 1.4986)
			(layers "F.Cu" "F.Mask" "F.Paste")
			(net "M_B_CPU0_SB_DQ<16>")
		)
		(pad "123" smd rect
			(at -2.050034 45.47489 90)
			(size 0.519938 1.4986)
			(layers "F.Cu" "F.Mask" "F.Paste")
			(net "GND")
		)
		(pad "124" smd rect
			(at -2.050034 46.325028 90)
			(size 0.519938 1.4986)
			(layers "F.Cu" "F.Mask" "F.Paste")
			(net "M_B_CPU0_SB_DQ<17>")
		)
		(pad "125" smd rect
			(at -2.050034 47.174912 90)
			(size 0.519938 1.4986)
			(layers "F.Cu" "F.Mask" "F.Paste")
			(net "GND")
		)
		(pad "126" smd rect
			(at -2.050034 48.02505 90)
			(size 0.519938 1.4986)
			(layers "F.Cu" "F.Mask" "F.Paste")
			(net "M_B_CPU0_SB_DQS_DP<2>")
		)
		(pad "127" smd rect
			(at -2.050034 48.874934 90)
			(size 0.519938 1.4986)
			(layers "F.Cu" "F.Mask" "F.Paste")
			(net "M_B_CPU0_SB_DQS_DN<2>")
		)
		(pad "128" smd rect
			(at -2.050034 49.725072 90)
			(size 0.519938 1.4986)
			(layers "F.Cu" "F.Mask" "F.Paste")
			(net "GND")
		)
		(pad "129" smd rect
			(at -2.050034 50.574956 90)
			(size 0.519938 1.4986)
			(layers "F.Cu" "F.Mask" "F.Paste")
			(net "M_B_CPU0_SB_DQ<20>")
		)
		(pad "130" smd rect
			(at -2.050034 51.425094 90)
			(size 0.519938 1.4986)
			(layers "F.Cu" "F.Mask" "F.Paste")
			(net "GND")
		)
		(pad "131" smd rect
			(at -2.050034 52.274978 90)
			(size 0.519938 1.4986)
			(layers "F.Cu" "F.Mask" "F.Paste")
			(net "M_B_CPU0_SB_DQ<21>")
		)
		(pad "132" smd rect
			(at -2.050034 53.125116 90)
			(size 0.519938 1.4986)
			(layers "F.Cu" "F.Mask" "F.Paste")
			(net "GND")
		)
		(pad "133" smd rect
			(at -2.050034 53.975 90)
			(size 0.519938 1.4986)
			(layers "F.Cu" "F.Mask" "F.Paste")
			(net "M_B_CPU0_SB_DQ<24>")
		)
		(pad "134" smd rect
			(at -2.050034 54.824884 90)
			(size 0.519938 1.4986)
			(layers "F.Cu" "F.Mask" "F.Paste")
			(net "GND")
		)
		(pad "135" smd rect
			(at -2.050034 55.675022 90)
			(size 0.519938 1.4986)
			(layers "F.Cu" "F.Mask" "F.Paste")
			(net "M_B_CPU0_SB_DQ<25>")
		)
		(pad "136" smd rect
			(at -2.050034 56.524906 90)
			(size 0.519938 1.4986)
			(layers "F.Cu" "F.Mask" "F.Paste")
			(net "GND")
		)
		(pad "137" smd rect
			(at -2.050034 57.375044 90)
			(size 0.519938 1.4986)
			(layers "F.Cu" "F.Mask" "F.Paste")
			(net "M_B_CPU0_SB_DQS_DP<3>")
		)
		(pad "138" smd rect
			(at -2.050034 58.224928 90)
			(size 0.519938 1.4986)
			(layers "F.Cu" "F.Mask" "F.Paste")
			(net "M_B_CPU0_SB_DQS_DN<3>")
		)
	)
)
